(kicad_pcb
	(version 20260206)
	(generator "pcbnew")
	(generator_version "10.0")
	(general
		(thickness 1.6)
		(legacy_teardrops no)
	)
	(paper "A4")
	(title_block
		(title "03242023_DA0F0TMBIJ0_F0T_Motherboard_J_brd_V01_OCP.brd")
		(comment 1 "Grand Teton / footprints 4629-4635 of 6105")
	)
	(layers
		(0 "F.Cu" signal "TOP")
		(4 "In1.Cu" signal "GND")
		(6 "In2.Cu" signal "IN1")
		(8 "In3.Cu" signal "GND1")
		(10 "In4.Cu" signal "IN2")
		(12 "In5.Cu" signal "GND2")
		(14 "In6.Cu" signal "IN3")
		(16 "In7.Cu" signal "GND3")
		(18 "In8.Cu" signal "VCC")
		(20 "In9.Cu" signal "VCC1")
		(22 "In10.Cu" signal "GND4")
		(24 "In11.Cu" signal "IN4")
		(26 "In12.Cu" signal "GND5")
		(28 "In13.Cu" signal "IN5")
		(30 "In14.Cu" signal "GND6")
		(32 "In15.Cu" signal "IN6")
		(34 "In16.Cu" signal "GND7")
		(2 "B.Cu" signal "BOTTOM")
		(9 "F.Adhes" user "F.Adhesive")
		(11 "B.Adhes" user "B.Adhesive")
		(13 "F.Paste" user "Package Geometry/Pastemask Top")
		(15 "B.Paste" user "Package Geometry/Pastemask Bottom")
		(5 "F.SilkS" user "Ref Des/Silkscreen Top")
		(7 "B.SilkS" user "Ref Des/Silkscreen Bottom")
		(1 "F.Mask" user "Board Geometry/Soldermask Top")
		(3 "B.Mask" user "Board Geometry/Soldermask Bottom")
		(17 "Dwgs.User" user "User.Drawings")
		(19 "Cmts.User" user "User.Comments")
		(21 "Eco1.User" user "User.Eco1")
		(23 "Eco2.User" user "User.Eco2")
		(25 "Edge.Cuts" user "Board Geometry/Outline")
		(27 "Margin" user)
		(31 "F.CrtYd" user "Package Geometry/Place Bound Top")
		(29 "B.CrtYd" user "Package Geometry/Place Bound Bottom")
		(35 "F.Fab" user "Ref Des/Assembly Top")
		(33 "B.Fab" user "Ref Des/Assembly Bottom")
	)
	(footprint ""
		(layer "B.Cu")
		(at 282.423616 -318.94653 90)
		(property "Reference" "R2730"
			(at 0 0 90)
			(layer "B.SilkS")
			(hide yes)
			(effects
				(font
					(size 1.27 1.27)
				)
				(justify mirror)
			)
		)
		(property "Value" ""
			(at 0 0 90)
			(layer "B.Fab")
			(effects
				(font
					(size 1.27 1.27)
				)
				(justify mirror)
			)
		)
		(duplicate_pad_numbers_are_jumpers no)
		(fp_line
			(start 0.7874 -0.4064)
			(end -0.7874 -0.4064)
			(stroke
				(width 0.1524)
				(type default)
			)
			(layer "B.SilkS")
		)
		(fp_line
			(start -0.7874 -0.4064)
			(end -0.7874 0.4064)
			(stroke
				(width 0.1524)
				(type default)
			)
			(layer "B.SilkS")
		)
		(fp_line
			(start 0.7874 0.4064)
			(end 0.7874 -0.4064)
			(stroke
				(width 0.1524)
				(type default)
			)
			(layer "B.SilkS")
		)
		(fp_line
			(start -0.7874 0.4064)
			(end 0.7874 0.4064)
			(stroke
				(width 0.1524)
				(type default)
			)
			(layer "B.SilkS")
		)
		(fp_line
			(start 0.67945 -0.305054)
			(end 0.12065 -0.305054)
			(stroke
				(width 0.1)
				(type default)
			)
			(layer "B.Fab")
		)
		(fp_line
			(start 0.12065 -0.305054)
			(end 0.12065 -0.2794)
			(stroke
				(width 0.1)
				(type default)
			)
			(layer "B.Fab")
		)
		(fp_line
			(start -0.12065 -0.3048)
			(end -0.67945 -0.3048)
			(stroke
				(width 0.1)
				(type default)
			)
			(layer "B.Fab")
		)
		(fp_line
			(start -0.67945 -0.3048)
			(end -0.67945 0.3048)
			(stroke
				(width 0.1)
				(type default)
			)
			(layer "B.Fab")
		)
		(fp_line
			(start 0.12065 -0.2794)
			(end -0.12065 -0.2794)
			(stroke
				(width 0.1)
				(type default)
			)
			(layer "B.Fab")
		)
		(fp_line
			(start -0.12065 -0.2794)
			(end -0.12065 -0.3048)
			(stroke
				(width 0.1)
				(type default)
			)
			(layer "B.Fab")
		)
		(fp_line
			(start 0.12065 0.2794)
			(end 0.12065 0.3048)
			(stroke
				(width 0.1)
				(type default)
			)
			(layer "B.Fab")
		)
		(fp_line
			(start -0.120396 0.2794)
			(end 0.12065 0.2794)
			(stroke
				(width 0.1)
				(type default)
			)
			(layer "B.Fab")
		)
		(fp_line
			(start 0.67945 0.3048)
			(end 0.67945 -0.305054)
			(stroke
				(width 0.1)
				(type default)
			)
			(layer "B.Fab")
		)
		(fp_line
			(start 0.12065 0.3048)
			(end 0.67945 0.3048)
			(stroke
				(width 0.1)
				(type default)
			)
			(layer "B.Fab")
		)
		(fp_line
			(start -0.120396 0.3048)
			(end -0.120396 0.2794)
			(stroke
				(width 0.1)
				(type default)
			)
			(layer "B.Fab")
		)
		(fp_line
			(start -0.67945 0.3048)
			(end -0.120396 0.3048)
			(stroke
				(width 0.1)
				(type default)
			)
			(layer "B.Fab")
		)
		(pad "1" smd circle
			(at 0.40005 0 270)
			(size 0 0)
			(layers "B.Cu" "B.Mask" "B.Paste")
			(net "PWRGD_CHC_CPU0_DIMM2")
		)
		(pad "2" smd circle
			(at -0.40005 0 270)
			(size 0 0)
			(layers "B.Cu" "B.Mask" "B.Paste")
			(net "PWRGD_FAIL_CPU0_CD")
		)
	)
	(footprint ""
		(layer "B.Cu")
		(at 304.718466 -319.061846 90)
		(property "Reference" "R2726"
			(at 0 0 90)
			(layer "B.SilkS")
			(hide yes)
			(effects
				(font
					(size 1.27 1.27)
				)
				(justify mirror)
			)
		)
		(property "Value" ""
			(at 0 0 90)
			(layer "B.Fab")
			(effects
				(font
					(size 1.27 1.27)
				)
				(justify mirror)
			)
		)
		(duplicate_pad_numbers_are_jumpers no)
		(fp_line
			(start 0.7874 -0.4064)
			(end -0.7874 -0.4064)
			(stroke
				(width 0.1524)
				(type default)
			)
			(layer "B.SilkS")
		)
		(fp_line
			(start -0.7874 -0.4064)
			(end -0.7874 0.4064)
			(stroke
				(width 0.1524)
				(type default)
			)
			(layer "B.SilkS")
		)
		(fp_line
			(start 0.7874 0.4064)
			(end 0.7874 -0.4064)
			(stroke
				(width 0.1524)
				(type default)
			)
			(layer "B.SilkS")
		)
		(fp_line
			(start -0.7874 0.4064)
			(end 0.7874 0.4064)
			(stroke
				(width 0.1524)
				(type default)
			)
			(layer "B.SilkS")
		)
		(fp_line
			(start 0.67945 -0.305054)
			(end 0.12065 -0.305054)
			(stroke
				(width 0.1)
				(type default)
			)
			(layer "B.Fab")
		)
		(fp_line
			(start 0.12065 -0.305054)
			(end 0.12065 -0.2794)
			(stroke
				(width 0.1)
				(type default)
			)
			(layer "B.Fab")
		)
		(fp_line
			(start -0.12065 -0.3048)
			(end -0.67945 -0.3048)
			(stroke
				(width 0.1)
				(type default)
			)
			(layer "B.Fab")
		)
		(fp_line
			(start -0.67945 -0.3048)
			(end -0.67945 0.3048)
			(stroke
				(width 0.1)
				(type default)
			)
			(layer "B.Fab")
		)
		(fp_line
			(start 0.12065 -0.2794)
			(end -0.12065 -0.2794)
			(stroke
				(width 0.1)
				(type default)
			)
			(layer "B.Fab")
		)
		(fp_line
			(start -0.12065 -0.2794)
			(end -0.12065 -0.3048)
			(stroke
				(width 0.1)
				(type default)
			)
			(layer "B.Fab")
		)
		(fp_line
			(start 0.12065 0.2794)
			(end 0.12065 0.3048)
			(stroke
				(width 0.1)
				(type default)
			)
			(layer "B.Fab")
		)
		(fp_line
			(start -0.120396 0.2794)
			(end 0.12065 0.2794)
			(stroke
				(width 0.1)
				(type default)
			)
			(layer "B.Fab")
		)
		(fp_line
			(start 0.67945 0.3048)
			(end 0.67945 -0.305054)
			(stroke
				(width 0.1)
				(type default)
			)
			(layer "B.Fab")
		)
		(fp_line
			(start 0.12065 0.3048)
			(end 0.67945 0.3048)
			(stroke
				(width 0.1)
				(type default)
			)
			(layer "B.Fab")
		)
		(fp_line
			(start -0.120396 0.3048)
			(end -0.120396 0.2794)
			(stroke
				(width 0.1)
				(type default)
			)
			(layer "B.Fab")
		)
		(fp_line
			(start -0.67945 0.3048)
			(end -0.120396 0.3048)
			(stroke
				(width 0.1)
				(type default)
			)
			(layer "B.Fab")
		)
		(pad "1" smd circle
			(at 0.40005 0 270)
			(size 0 0)
			(layers "B.Cu" "B.Mask" "B.Paste")
			(net "PWRGD_CHA_CPU0_DIMM1")
		)
		(pad "2" smd circle
			(at -0.40005 0 270)
			(size 0 0)
			(layers "B.Cu" "B.Mask" "B.Paste")
			(net "PWRGD_FAIL_CPU0_AB")
		)
	)
	(footprint ""
		(layer "B.Cu")
		(at 367.898934 -252.176026 -90)
		(property "Reference" "C370"
			(at 0 0 90)
			(layer "B.SilkS")
			(hide yes)
			(effects
				(font
					(size 1.27 1.27)
				)
				(justify mirror)
			)
		)
		(property "Value" ""
			(at 0 0 90)
			(layer "B.Fab")
			(effects
				(font
					(size 1.27 1.27)
				)
				(justify mirror)
			)
		)
		(duplicate_pad_numbers_are_jumpers no)
		(fp_line
			(start -1.524 0.762)
			(end 1.524 0.762)
			(stroke
				(width 0.1524)
				(type default)
			)
			(layer "B.SilkS")
		)
		(fp_line
			(start 1.524 0.762)
			(end 1.524 -0.762)
			(stroke
				(width 0.1524)
				(type default)
			)
			(layer "B.SilkS")
		)
		(fp_line
			(start -1.524 -0.762)
			(end -1.524 0.762)
			(stroke
				(width 0.1524)
				(type default)
			)
			(layer "B.SilkS")
		)
		(fp_line
			(start 1.524 -0.762)
			(end -1.524 -0.762)
			(stroke
				(width 0.1524)
				(type default)
			)
			(layer "B.SilkS")
		)
		(fp_line
			(start -1.1049 0.724916)
			(end -1.1049 -0.724916)
			(stroke
				(width 0.1)
				(type default)
			)
			(layer "B.Fab")
		)
		(fp_line
			(start 1.1049 0.724916)
			(end -1.1049 0.724916)
			(stroke
				(width 0.1)
				(type default)
			)
			(layer "B.Fab")
		)
		(fp_line
			(start -1.1049 -0.724916)
			(end 1.1049 -0.724916)
			(stroke
				(width 0.1)
				(type default)
			)
			(layer "B.Fab")
		)
		(fp_line
			(start 1.1049 -0.724916)
			(end 1.1049 0.724916)
			(stroke
				(width 0.1)
				(type default)
			)
			(layer "B.Fab")
		)
		(pad "1" smd rect
			(at 0.889 0 270)
			(size 1.016 1.27)
			(layers "B.Cu" "B.Mask" "B.Paste")
			(net "PVCCIN_CPU0")
		)
		(pad "2" smd rect
			(at -0.889 0 270)
			(size 1.016 1.27)
			(layers "B.Cu" "B.Mask" "B.Paste")
			(net "GND")
		)
	)
	(footprint ""
		(layer "B.Cu")
		(at 366.037368 -262.348726 180)
		(property "Reference" "C1396"
			(at 0 0 0)
			(layer "B.SilkS")
			(hide yes)
			(effects
				(font
					(size 1.27 1.27)
				)
				(justify mirror)
			)
		)
		(property "Value" ""
			(at 0 0 0)
			(layer "B.Fab")
			(effects
				(font
					(size 1.27 1.27)
				)
				(justify mirror)
			)
		)
		(duplicate_pad_numbers_are_jumpers no)
		(fp_line
			(start 1.524 0.762)
			(end 1.524 -0.762)
			(stroke
				(width 0.1524)
				(type default)
			)
			(layer "B.SilkS")
		)
		(fp_line
			(start 1.524 -0.762)
			(end -1.524 -0.762)
			(stroke
				(width 0.1524)
				(type default)
			)
			(layer "B.SilkS")
		)
		(fp_line
			(start -1.524 0.762)
			(end 1.524 0.762)
			(stroke
				(width 0.1524)
				(type default)
			)
			(layer "B.SilkS")
		)
		(fp_line
			(start -1.524 -0.762)
			(end -1.524 0.762)
			(stroke
				(width 0.1524)
				(type default)
			)
			(layer "B.SilkS")
		)
		(fp_line
			(start 1.1049 0.724916)
			(end -1.1049 0.724916)
			(stroke
				(width 0.1)
				(type default)
			)
			(layer "B.Fab")
		)
		(fp_line
			(start 1.1049 -0.724916)
			(end 1.1049 0.724916)
			(stroke
				(width 0.1)
				(type default)
			)
			(layer "B.Fab")
		)
		(fp_line
			(start -1.1049 0.724916)
			(end -1.1049 -0.724916)
			(stroke
				(width 0.1)
				(type default)
			)
			(layer "B.Fab")
		)
		(fp_line
			(start -1.1049 -0.724916)
			(end 1.1049 -0.724916)
			(stroke
				(width 0.1)
				(type default)
			)
			(layer "B.Fab")
		)
		(pad "1" smd rect
			(at 0.889 0 180)
			(size 1.016 1.27)
			(layers "B.Cu" "B.Mask" "B.Paste")
			(net "PVPP_HBM_CPU0")
		)
		(pad "2" smd rect
			(at -0.889 0 180)
			(size 1.016 1.27)
			(layers "B.Cu" "B.Mask" "B.Paste")
			(net "GND")
		)
	)
	(footprint ""
		(layer "B.Cu")
		(at 364.04804 -185.981848 180)
		(property "Reference" "R1006"
			(at 0 0 0)
			(layer "B.SilkS")
			(hide yes)
			(effects
				(font
					(size 1.27 1.27)
				)
				(justify mirror)
			)
		)
		(property "Value" ""
			(at 0 0 0)
			(layer "B.Fab")
			(effects
				(font
					(size 1.27 1.27)
				)
				(justify mirror)
			)
		)
		(duplicate_pad_numbers_are_jumpers no)
		(fp_line
			(start 0.7874 0.4064)
			(end 0.7874 -0.4064)
			(stroke
				(width 0.1524)
				(type default)
			)
			(layer "B.SilkS")
		)
		(fp_line
			(start 0.7874 -0.4064)
			(end -0.7874 -0.4064)
			(stroke
				(width 0.1524)
				(type default)
			)
			(layer "B.SilkS")
		)
		(fp_line
			(start -0.7874 0.4064)
			(end 0.7874 0.4064)
			(stroke
				(width 0.1524)
				(type default)
			)
			(layer "B.SilkS")
		)
		(fp_line
			(start -0.7874 -0.4064)
			(end -0.7874 0.4064)
			(stroke
				(width 0.1524)
				(type default)
			)
			(layer "B.SilkS")
		)
		(fp_line
			(start 0.67945 0.3048)
			(end 0.67945 -0.305054)
			(stroke
				(width 0.1)
				(type default)
			)
			(layer "B.Fab")
		)
		(fp_line
			(start 0.67945 -0.305054)
			(end 0.12065 -0.305054)
			(stroke
				(width 0.1)
				(type default)
			)
			(layer "B.Fab")
		)
		(fp_line
			(start 0.12065 0.3048)
			(end 0.67945 0.3048)
			(stroke
				(width 0.1)
				(type default)
			)
			(layer "B.Fab")
		)
		(fp_line
			(start 0.12065 0.2794)
			(end 0.12065 0.3048)
			(stroke
				(width 0.1)
				(type default)
			)
			(layer "B.Fab")
		)
		(fp_line
			(start 0.12065 -0.2794)
			(end -0.12065 -0.2794)
			(stroke
				(width 0.1)
				(type default)
			)
			(layer "B.Fab")
		)
		(fp_line
			(start 0.12065 -0.305054)
			(end 0.12065 -0.2794)
			(stroke
				(width 0.1)
				(type default)
			)
			(layer "B.Fab")
		)
		(fp_line
			(start -0.120396 0.3048)
			(end -0.120396 0.2794)
			(stroke
				(width 0.1)
				(type default)
			)
			(layer "B.Fab")
		)
		(fp_line
			(start -0.120396 0.2794)
			(end 0.12065 0.2794)
			(stroke
				(width 0.1)
				(type default)
			)
			(layer "B.Fab")
		)
		(fp_line
			(start -0.12065 -0.2794)
			(end -0.12065 -0.3048)
			(stroke
				(width 0.1)
				(type default)
			)
			(layer "B.Fab")
		)
		(fp_line
			(start -0.12065 -0.3048)
			(end -0.67945 -0.3048)
			(stroke
				(width 0.1)
				(type default)
			)
			(layer "B.Fab")
		)
		(fp_line
			(start -0.67945 0.3048)
			(end -0.120396 0.3048)
			(stroke
				(width 0.1)
				(type default)
			)
			(layer "B.Fab")
		)
		(fp_line
			(start -0.67945 -0.3048)
			(end -0.67945 0.3048)
			(stroke
				(width 0.1)
				(type default)
			)
			(layer "B.Fab")
		)
		(pad "1" smd circle
			(at 0.40005 0)
			(size 0 0)
			(layers "B.Cu" "B.Mask" "B.Paste")
			(net "PVNN_TERM_CPU0")
		)
		(pad "2" smd circle
			(at -0.40005 0)
			(size 0 0)
			(layers "B.Cu" "B.Mask" "B.Paste")
			(net "FM_PEHPCPU0_ALERT_N")
		)
	)
	(footprint ""
		(layer "B.Cu")
		(at 27.0383 -128.364996 180)
		(property "Reference" "PR261"
			(at 0 0 0)
			(layer "B.SilkS")
			(hide yes)
			(effects
				(font
					(size 1.27 1.27)
				)
				(justify mirror)
			)
		)
		(property "Value" ""
			(at 0 0 0)
			(layer "B.Fab")
			(effects
				(font
					(size 1.27 1.27)
				)
				(justify mirror)
			)
		)
		(duplicate_pad_numbers_are_jumpers no)
		(fp_line
			(start 0.7874 0.4064)
			(end 0.7874 -0.4064)
			(stroke
				(width 0.1524)
				(type default)
			)
			(layer "B.SilkS")
		)
		(fp_line
			(start 0.7874 -0.4064)
			(end -0.7874 -0.4064)
			(stroke
				(width 0.1524)
				(type default)
			)
			(layer "B.SilkS")
		)
		(fp_line
			(start -0.7874 0.4064)
			(end 0.7874 0.4064)
			(stroke
				(width 0.1524)
				(type default)
			)
			(layer "B.SilkS")
		)
		(fp_line
			(start -0.7874 -0.4064)
			(end -0.7874 0.4064)
			(stroke
				(width 0.1524)
				(type default)
			)
			(layer "B.SilkS")
		)
		(fp_line
			(start 0.67945 0.3048)
			(end 0.67945 -0.305054)
			(stroke
				(width 0.1)
				(type default)
			)
			(layer "B.Fab")
		)
		(fp_line
			(start 0.67945 -0.305054)
			(end 0.12065 -0.305054)
			(stroke
				(width 0.1)
				(type default)
			)
			(layer "B.Fab")
		)
		(fp_line
			(start 0.12065 0.3048)
			(end 0.67945 0.3048)
			(stroke
				(width 0.1)
				(type default)
			)
			(layer "B.Fab")
		)
		(fp_line
			(start 0.12065 0.2794)
			(end 0.12065 0.3048)
			(stroke
				(width 0.1)
				(type default)
			)
			(layer "B.Fab")
		)
		(fp_line
			(start 0.12065 -0.2794)
			(end -0.12065 -0.2794)
			(stroke
				(width 0.1)
				(type default)
			)
			(layer "B.Fab")
		)
		(fp_line
			(start 0.12065 -0.305054)
			(end 0.12065 -0.2794)
			(stroke
				(width 0.1)
				(type default)
			)
			(layer "B.Fab")
		)
		(fp_line
			(start -0.120396 0.3048)
			(end -0.120396 0.2794)
			(stroke
				(width 0.1)
				(type default)
			)
			(layer "B.Fab")
		)
		(fp_line
			(start -0.120396 0.2794)
			(end 0.12065 0.2794)
			(stroke
				(width 0.1)
				(type default)
			)
			(layer "B.Fab")
		)
		(fp_line
			(start -0.12065 -0.2794)
			(end -0.12065 -0.3048)
			(stroke
				(width 0.1)
				(type default)
			)
			(layer "B.Fab")
		)
		(fp_line
			(start -0.12065 -0.3048)
			(end -0.67945 -0.3048)
			(stroke
				(width 0.1)
				(type default)
			)
			(layer "B.Fab")
		)
		(fp_line
			(start -0.67945 0.3048)
			(end -0.120396 0.3048)
			(stroke
				(width 0.1)
				(type default)
			)
			(layer "B.Fab")
		)
		(fp_line
			(start -0.67945 -0.3048)
			(end -0.67945 0.3048)
			(stroke
				(width 0.1)
				(type default)
			)
			(layer "B.Fab")
		)
		(pad "1" smd circle
			(at 0.40005 0)
			(size 0 0)
			(layers "B.Cu" "B.Mask" "B.Paste")
			(net "P12V_AUX")
		)
		(pad "2" smd circle
			(at -0.40005 0)
			(size 0 0)
			(layers "B.Cu" "B.Mask" "B.Paste")
			(net "PVCCINFAON_CPU1_VIN_CSNIN")
		)
	)
	(footprint ""
		(layer "B.Cu")
		(at 181.755542 -114.575336)
		(property "Reference" "C1127"
			(at 0 0 0)
			(layer "B.SilkS")
			(hide yes)
			(effects
				(font
					(size 1.27 1.27)
				)
				(justify mirror)
			)
		)
		(property "Value" ""
			(at 0 0 0)
			(layer "B.Fab")
			(effects
				(font
					(size 1.27 1.27)
				)
				(justify mirror)
			)
		)
		(duplicate_pad_numbers_are_jumpers no)
		(fp_line
			(start -0.69215 -0.2921)
			(end -0.69215 0.2921)
			(stroke
				(width 0.1524)
				(type default)
			)
			(layer "B.SilkS")
		)
		(fp_line
			(start -0.69215 0.2921)
			(end 0.69215 0.2921)
			(stroke
				(width 0.1524)
				(type default)
			)
			(layer "B.SilkS")
		)
		(fp_line
			(start 0.69215 -0.2921)
			(end -0.69215 -0.2921)
			(stroke
				(width 0.1524)
				(type default)
			)
			(layer "B.SilkS")
		)
		(fp_line
			(start 0.69215 0.2921)
			(end 0.69215 -0.2921)
			(stroke
				(width 0.1524)
				(type default)
			)
			(layer "B.SilkS")
		)
		(fp_line
			(start -0.51435 -0.2794)
			(end -0.51435 0.2794)
			(stroke
				(width 0.1)
				(type default)
			)
			(layer "B.Fab")
		)
		(fp_line
			(start -0.51435 0.2794)
			(end 0.51435 0.2794)
			(stroke
				(width 0.1)
				(type default)
			)
			(layer "B.Fab")
		)
		(fp_line
			(start 0.51435 -0.2794)
			(end -0.51435 -0.2794)
			(stroke
				(width 0.1)
				(type default)
			)
			(layer "B.Fab")
		)
		(fp_line
			(start 0.51435 0.2794)
			(end 0.51435 -0.2794)
			(stroke
				(width 0.1)
				(type default)
			)
			(layer "B.Fab")
		)
		(pad "1" smd circle
			(at 0.40005 0 180)
			(size 0 0)
			(layers "B.Cu" "B.Mask" "B.Paste")
			(net "P3V3_AUX_FPGA_VCCIO2")
		)
		(pad "2" smd circle
			(at -0.40005 0 180)
			(size 0 0)
			(layers "B.Cu" "B.Mask" "B.Paste")
			(net "GND")
		)
		(zone
			(layer "B.Cu")
			(hatch none 0.5)
			(connect_pads
				(clearance 0)
			)
			(min_thickness 0.25)
			(keepout
				(tracks not_allowed)
				(vias allowed)
				(pads allowed)
				(copperpour not_allowed)
				(footprints allowed)
			)
			(placement
				(enabled no)
				(sheetname "")
			)
			(fill
				(thermal_gap 0.5)
				(thermal_bridge_width 0.5)
				(island_removal_mode 0)
			)
			(polygon
				(pts
					(xy 181.946042 -114.487706) (xy 181.854602 -114.42954) (xy 181.655212 -114.42954) (xy 181.565042 -114.487706)
					(xy 181.565042 -114.662966) (xy 181.655212 -114.721386) (xy 181.854602 -114.721386) (xy 181.946042 -114.66322)
				)
			)
		)
	)
)
